(kicad_pcb
	(version 20260206)
	(generator "pcbnew")
	(generator_version "10.0")
	(general
		(thickness 1.6)
		(legacy_teardrops no)
	)
	(paper "A4")
	(title_block
		(title "04192023_DAF0TMB3IC0_F0TG_MB_C_brd_V02_OCP.brd")
		(comment 1 "Grand Teton / footprints 5673-5678 of 8354")
	)
	(layers
		(0 "F.Cu" signal "TOP")
		(4 "In1.Cu" signal "GND")
		(6 "In2.Cu" signal "IN1")
		(8 "In3.Cu" signal "GND1")
		(10 "In4.Cu" signal "IN2")
		(12 "In5.Cu" signal "GND2")
		(14 "In6.Cu" signal "IN3")
		(16 "In7.Cu" signal "GND3")
		(18 "In8.Cu" signal "VCC")
		(20 "In9.Cu" signal "VCC1")
		(22 "In10.Cu" signal "GND4")
		(24 "In11.Cu" signal "IN4")
		(26 "In12.Cu" signal "GND5")
		(28 "In13.Cu" signal "IN5")
		(30 "In14.Cu" signal "GND6")
		(32 "In15.Cu" signal "IN6")
		(34 "In16.Cu" signal "GND7")
		(2 "B.Cu" signal "BOTTOM")
		(9 "F.Adhes" user "F.Adhesive")
		(11 "B.Adhes" user "B.Adhesive")
		(13 "F.Paste" user "Package Geometry/Pastemask Top")
		(15 "B.Paste" user "Package Geometry/Pastemask Bottom")
		(5 "F.SilkS" user "Ref Des/Silkscreen Top")
		(7 "B.SilkS" user "Ref Des/Silkscreen Bottom")
		(1 "F.Mask" user "Board Geometry/Soldermask Top")
		(3 "B.Mask" user "Board Geometry/Soldermask Bottom")
		(17 "Dwgs.User" user "User.Drawings")
		(19 "Cmts.User" user "User.Comments")
		(21 "Eco1.User" user "User.Eco1")
		(23 "Eco2.User" user "User.Eco2")
		(25 "Edge.Cuts" user "Board Geometry/Outline")
		(27 "Margin" user)
		(31 "F.CrtYd" user "Package Geometry/Place Bound Top")
		(29 "B.CrtYd" user "Package Geometry/Place Bound Bottom")
		(35 "F.Fab" user "Ref Des/Assembly Top")
		(33 "B.Fab" user "Ref Des/Assembly Bottom")
	)
	(footprint ""
		(layer "B.Cu")
		(at 367.995454 -268.41831)
		(property "Reference" "C2232"
			(at 0 0 0)
			(layer "B.SilkS")
			(hide yes)
			(effects
				(font
					(size 1.27 1.27)
				)
				(justify mirror)
			)
		)
		(property "Value" ""
			(at 0 0 0)
			(layer "B.Fab")
			(effects
				(font
					(size 1.27 1.27)
				)
				(justify mirror)
			)
		)
		(duplicate_pad_numbers_are_jumpers no)
		(fp_line
			(start -0.7874 -0.4064)
			(end -0.7874 0.4064)
			(stroke
				(width 0.1524)
				(type default)
			)
			(layer "B.SilkS")
		)
		(fp_line
			(start -0.7874 0.4064)
			(end 0.7874 0.4064)
			(stroke
				(width 0.1524)
				(type default)
			)
			(layer "B.SilkS")
		)
		(fp_line
			(start 0.7874 -0.4064)
			(end -0.7874 -0.4064)
			(stroke
				(width 0.1524)
				(type default)
			)
			(layer "B.SilkS")
		)
		(fp_line
			(start 0.7874 0.4064)
			(end 0.7874 -0.4064)
			(stroke
				(width 0.1524)
				(type default)
			)
			(layer "B.SilkS")
		)
		(fp_line
			(start -0.67945 -0.3048)
			(end -0.67945 0.3048)
			(stroke
				(width 0.1)
				(type default)
			)
			(layer "B.Fab")
		)
		(fp_line
			(start -0.67945 0.3048)
			(end -0.120396 0.3048)
			(stroke
				(width 0.1)
				(type default)
			)
			(layer "B.Fab")
		)
		(fp_line
			(start -0.12065 -0.3048)
			(end -0.67945 -0.3048)
			(stroke
				(width 0.1)
				(type default)
			)
			(layer "B.Fab")
		)
		(fp_line
			(start -0.12065 -0.2794)
			(end -0.12065 -0.3048)
			(stroke
				(width 0.1)
				(type default)
			)
			(layer "B.Fab")
		)
		(fp_line
			(start -0.120396 0.2794)
			(end 0.12065 0.2794)
			(stroke
				(width 0.1)
				(type default)
			)
			(layer "B.Fab")
		)
		(fp_line
			(start -0.120396 0.3048)
			(end -0.120396 0.2794)
			(stroke
				(width 0.1)
				(type default)
			)
			(layer "B.Fab")
		)
		(fp_line
			(start 0.12065 -0.305054)
			(end 0.12065 -0.2794)
			(stroke
				(width 0.1)
				(type default)
			)
			(layer "B.Fab")
		)
		(fp_line
			(start 0.12065 -0.2794)
			(end -0.12065 -0.2794)
			(stroke
				(width 0.1)
				(type default)
			)
			(layer "B.Fab")
		)
		(fp_line
			(start 0.12065 0.2794)
			(end 0.12065 0.3048)
			(stroke
				(width 0.1)
				(type default)
			)
			(layer "B.Fab")
		)
		(fp_line
			(start 0.12065 0.3048)
			(end 0.67945 0.3048)
			(stroke
				(width 0.1)
				(type default)
			)
			(layer "B.Fab")
		)
		(fp_line
			(start 0.67945 -0.305054)
			(end 0.12065 -0.305054)
			(stroke
				(width 0.1)
				(type default)
			)
			(layer "B.Fab")
		)
		(fp_line
			(start 0.67945 0.3048)
			(end 0.67945 -0.305054)
			(stroke
				(width 0.1)
				(type default)
			)
			(layer "B.Fab")
		)
		(pad "1" smd circle
			(at 0.40005 0 180)
			(size 0 0)
			(layers "B.Cu" "B.Mask" "B.Paste")
			(net "PVDDCR_CPU1_P0")
		)
		(pad "2" smd circle
			(at -0.40005 0 180)
			(size 0 0)
			(layers "B.Cu" "B.Mask" "B.Paste")
			(net "GND")
		)
	)
	(footprint ""
		(layer "B.Cu")
		(at 359.740454 -247.97131 90)
		(property "Reference" "C2193"
			(at 0 0 90)
			(layer "B.SilkS")
			(hide yes)
			(effects
				(font
					(size 1.27 1.27)
				)
				(justify mirror)
			)
		)
		(property "Value" ""
			(at 0 0 90)
			(layer "B.Fab")
			(effects
				(font
					(size 1.27 1.27)
				)
				(justify mirror)
			)
		)
		(duplicate_pad_numbers_are_jumpers no)
		(fp_line
			(start 0.7874 -0.4064)
			(end -0.7874 -0.4064)
			(stroke
				(width 0.1524)
				(type default)
			)
			(layer "B.SilkS")
		)
		(fp_line
			(start -0.7874 -0.4064)
			(end -0.7874 0.4064)
			(stroke
				(width 0.1524)
				(type default)
			)
			(layer "B.SilkS")
		)
		(fp_line
			(start 0.7874 0.4064)
			(end 0.7874 -0.4064)
			(stroke
				(width 0.1524)
				(type default)
			)
			(layer "B.SilkS")
		)
		(fp_line
			(start -0.7874 0.4064)
			(end 0.7874 0.4064)
			(stroke
				(width 0.1524)
				(type default)
			)
			(layer "B.SilkS")
		)
		(fp_line
			(start 0.67945 -0.305054)
			(end 0.12065 -0.305054)
			(stroke
				(width 0.1)
				(type default)
			)
			(layer "B.Fab")
		)
		(fp_line
			(start 0.12065 -0.305054)
			(end 0.12065 -0.2794)
			(stroke
				(width 0.1)
				(type default)
			)
			(layer "B.Fab")
		)
		(fp_line
			(start -0.12065 -0.3048)
			(end -0.67945 -0.3048)
			(stroke
				(width 0.1)
				(type default)
			)
			(layer "B.Fab")
		)
		(fp_line
			(start -0.67945 -0.3048)
			(end -0.67945 0.3048)
			(stroke
				(width 0.1)
				(type default)
			)
			(layer "B.Fab")
		)
		(fp_line
			(start 0.12065 -0.2794)
			(end -0.12065 -0.2794)
			(stroke
				(width 0.1)
				(type default)
			)
			(layer "B.Fab")
		)
		(fp_line
			(start -0.12065 -0.2794)
			(end -0.12065 -0.3048)
			(stroke
				(width 0.1)
				(type default)
			)
			(layer "B.Fab")
		)
		(fp_line
			(start 0.12065 0.2794)
			(end 0.12065 0.3048)
			(stroke
				(width 0.1)
				(type default)
			)
			(layer "B.Fab")
		)
		(fp_line
			(start -0.120396 0.2794)
			(end 0.12065 0.2794)
			(stroke
				(width 0.1)
				(type default)
			)
			(layer "B.Fab")
		)
		(fp_line
			(start 0.67945 0.3048)
			(end 0.67945 -0.305054)
			(stroke
				(width 0.1)
				(type default)
			)
			(layer "B.Fab")
		)
		(fp_line
			(start 0.12065 0.3048)
			(end 0.67945 0.3048)
			(stroke
				(width 0.1)
				(type default)
			)
			(layer "B.Fab")
		)
		(fp_line
			(start -0.120396 0.3048)
			(end -0.120396 0.2794)
			(stroke
				(width 0.1)
				(type default)
			)
			(layer "B.Fab")
		)
		(fp_line
			(start -0.67945 0.3048)
			(end -0.120396 0.3048)
			(stroke
				(width 0.1)
				(type default)
			)
			(layer "B.Fab")
		)
		(pad "1" smd circle
			(at 0.40005 0 270)
			(size 0 0)
			(layers "B.Cu" "B.Mask" "B.Paste")
			(net "PVDDCR_CPU0_P0")
		)
		(pad "2" smd circle
			(at -0.40005 0 270)
			(size 0 0)
			(layers "B.Cu" "B.Mask" "B.Paste")
			(net "GND")
		)
	)
	(footprint ""
		(layer "B.Cu")
		(at 371.551454 -258.830064)
		(property "Reference" "C2129"
			(at 0 0 0)
			(layer "B.SilkS")
			(hide yes)
			(effects
				(font
					(size 1.27 1.27)
				)
				(justify mirror)
			)
		)
		(property "Value" ""
			(at 0 0 0)
			(layer "B.Fab")
			(effects
				(font
					(size 1.27 1.27)
				)
				(justify mirror)
			)
		)
		(duplicate_pad_numbers_are_jumpers no)
		(fp_line
			(start -0.7874 -0.4064)
			(end -0.7874 0.4064)
			(stroke
				(width 0.1524)
				(type default)
			)
			(layer "B.SilkS")
		)
		(fp_line
			(start -0.7874 0.4064)
			(end 0.7874 0.4064)
			(stroke
				(width 0.1524)
				(type default)
			)
			(layer "B.SilkS")
		)
		(fp_line
			(start 0.7874 -0.4064)
			(end -0.7874 -0.4064)
			(stroke
				(width 0.1524)
				(type default)
			)
			(layer "B.SilkS")
		)
		(fp_line
			(start 0.7874 0.4064)
			(end 0.7874 -0.4064)
			(stroke
				(width 0.1524)
				(type default)
			)
			(layer "B.SilkS")
		)
		(fp_line
			(start -0.67945 -0.3048)
			(end -0.67945 0.3048)
			(stroke
				(width 0.1)
				(type default)
			)
			(layer "B.Fab")
		)
		(fp_line
			(start -0.67945 0.3048)
			(end -0.120396 0.3048)
			(stroke
				(width 0.1)
				(type default)
			)
			(layer "B.Fab")
		)
		(fp_line
			(start -0.12065 -0.3048)
			(end -0.67945 -0.3048)
			(stroke
				(width 0.1)
				(type default)
			)
			(layer "B.Fab")
		)
		(fp_line
			(start -0.12065 -0.2794)
			(end -0.12065 -0.3048)
			(stroke
				(width 0.1)
				(type default)
			)
			(layer "B.Fab")
		)
		(fp_line
			(start -0.120396 0.2794)
			(end 0.12065 0.2794)
			(stroke
				(width 0.1)
				(type default)
			)
			(layer "B.Fab")
		)
		(fp_line
			(start -0.120396 0.3048)
			(end -0.120396 0.2794)
			(stroke
				(width 0.1)
				(type default)
			)
			(layer "B.Fab")
		)
		(fp_line
			(start 0.12065 -0.305054)
			(end 0.12065 -0.2794)
			(stroke
				(width 0.1)
				(type default)
			)
			(layer "B.Fab")
		)
		(fp_line
			(start 0.12065 -0.2794)
			(end -0.12065 -0.2794)
			(stroke
				(width 0.1)
				(type default)
			)
			(layer "B.Fab")
		)
		(fp_line
			(start 0.12065 0.2794)
			(end 0.12065 0.3048)
			(stroke
				(width 0.1)
				(type default)
			)
			(layer "B.Fab")
		)
		(fp_line
			(start 0.12065 0.3048)
			(end 0.67945 0.3048)
			(stroke
				(width 0.1)
				(type default)
			)
			(layer "B.Fab")
		)
		(fp_line
			(start 0.67945 -0.305054)
			(end 0.12065 -0.305054)
			(stroke
				(width 0.1)
				(type default)
			)
			(layer "B.Fab")
		)
		(fp_line
			(start 0.67945 0.3048)
			(end 0.67945 -0.305054)
			(stroke
				(width 0.1)
				(type default)
			)
			(layer "B.Fab")
		)
		(pad "1" smd circle
			(at 0.40005 0 180)
			(size 0 0)
			(layers "B.Cu" "B.Mask" "B.Paste")
			(net "PVDDCR_SOC_P0")
		)
		(pad "2" smd circle
			(at -0.40005 0 180)
			(size 0 0)
			(layers "B.Cu" "B.Mask" "B.Paste")
			(net "GND")
		)
	)
	(footprint ""
		(layer "B.Cu")
		(at 171.440602 -8.062468 -90)
		(property "Reference" "R3243"
			(at 0 0 90)
			(layer "B.SilkS")
			(hide yes)
			(effects
				(font
					(size 1.27 1.27)
				)
				(justify mirror)
			)
		)
		(property "Value" ""
			(at 0 0 90)
			(layer "B.Fab")
			(effects
				(font
					(size 1.27 1.27)
				)
				(justify mirror)
			)
		)
		(duplicate_pad_numbers_are_jumpers no)
		(fp_line
			(start -0.7874 0.4064)
			(end 0.7874 0.4064)
			(stroke
				(width 0.1524)
				(type default)
			)
			(layer "B.SilkS")
		)
		(fp_line
			(start 0.7874 0.4064)
			(end 0.7874 -0.4064)
			(stroke
				(width 0.1524)
				(type default)
			)
			(layer "B.SilkS")
		)
		(fp_line
			(start -0.7874 -0.4064)
			(end -0.7874 0.4064)
			(stroke
				(width 0.1524)
				(type default)
			)
			(layer "B.SilkS")
		)
		(fp_line
			(start 0.7874 -0.4064)
			(end -0.7874 -0.4064)
			(stroke
				(width 0.1524)
				(type default)
			)
			(layer "B.SilkS")
		)
		(fp_line
			(start -0.67945 0.3048)
			(end -0.120396 0.3048)
			(stroke
				(width 0.1)
				(type default)
			)
			(layer "B.Fab")
		)
		(fp_line
			(start -0.120396 0.3048)
			(end -0.120396 0.2794)
			(stroke
				(width 0.1)
				(type default)
			)
			(layer "B.Fab")
		)
		(fp_line
			(start 0.12065 0.3048)
			(end 0.67945 0.3048)
			(stroke
				(width 0.1)
				(type default)
			)
			(layer "B.Fab")
		)
		(fp_line
			(start 0.67945 0.3048)
			(end 0.67945 -0.305054)
			(stroke
				(width 0.1)
				(type default)
			)
			(layer "B.Fab")
		)
		(fp_line
			(start -0.120396 0.2794)
			(end 0.12065 0.2794)
			(stroke
				(width 0.1)
				(type default)
			)
			(layer "B.Fab")
		)
		(fp_line
			(start 0.12065 0.2794)
			(end 0.12065 0.3048)
			(stroke
				(width 0.1)
				(type default)
			)
			(layer "B.Fab")
		)
		(fp_line
			(start -0.12065 -0.2794)
			(end -0.12065 -0.3048)
			(stroke
				(width 0.1)
				(type default)
			)
			(layer "B.Fab")
		)
		(fp_line
			(start 0.12065 -0.2794)
			(end -0.12065 -0.2794)
			(stroke
				(width 0.1)
				(type default)
			)
			(layer "B.Fab")
		)
		(fp_line
			(start -0.67945 -0.3048)
			(end -0.67945 0.3048)
			(stroke
				(width 0.1)
				(type default)
			)
			(layer "B.Fab")
		)
		(fp_line
			(start -0.12065 -0.3048)
			(end -0.67945 -0.3048)
			(stroke
				(width 0.1)
				(type default)
			)
			(layer "B.Fab")
		)
		(fp_line
			(start 0.12065 -0.305054)
			(end 0.12065 -0.2794)
			(stroke
				(width 0.1)
				(type default)
			)
			(layer "B.Fab")
		)
		(fp_line
			(start 0.67945 -0.305054)
			(end 0.12065 -0.305054)
			(stroke
				(width 0.1)
				(type default)
			)
			(layer "B.Fab")
		)
		(pad "1" smd circle
			(at 0.40005 0 90)
			(size 0 0)
			(layers "B.Cu" "B.Mask" "B.Paste")
			(net "SMB_OCP_V3_2_3V3AUX_SDA")
		)
		(pad "2" smd circle
			(at -0.40005 0 90)
			(size 0 0)
			(layers "B.Cu" "B.Mask" "B.Paste")
			(net "P3V3_AUX")
		)
	)
	(footprint ""
		(layer "B.Cu")
		(at 118.277386 -268.418564)
		(property "Reference" "C2375"
			(at 0 0 0)
			(layer "B.SilkS")
			(hide yes)
			(effects
				(font
					(size 1.27 1.27)
				)
				(justify mirror)
			)
		)
		(property "Value" ""
			(at 0 0 0)
			(layer "B.Fab")
			(effects
				(font
					(size 1.27 1.27)
				)
				(justify mirror)
			)
		)
		(duplicate_pad_numbers_are_jumpers no)
		(fp_line
			(start -0.7874 -0.4064)
			(end -0.7874 0.4064)
			(stroke
				(width 0.1524)
				(type default)
			)
			(layer "B.SilkS")
		)
		(fp_line
			(start -0.7874 0.4064)
			(end 0.7874 0.4064)
			(stroke
				(width 0.1524)
				(type default)
			)
			(layer "B.SilkS")
		)
		(fp_line
			(start 0.7874 -0.4064)
			(end -0.7874 -0.4064)
			(stroke
				(width 0.1524)
				(type default)
			)
			(layer "B.SilkS")
		)
		(fp_line
			(start 0.7874 0.4064)
			(end 0.7874 -0.4064)
			(stroke
				(width 0.1524)
				(type default)
			)
			(layer "B.SilkS")
		)
		(fp_line
			(start -0.67945 -0.3048)
			(end -0.67945 0.3048)
			(stroke
				(width 0.1)
				(type default)
			)
			(layer "B.Fab")
		)
		(fp_line
			(start -0.67945 0.3048)
			(end -0.120396 0.3048)
			(stroke
				(width 0.1)
				(type default)
			)
			(layer "B.Fab")
		)
		(fp_line
			(start -0.12065 -0.3048)
			(end -0.67945 -0.3048)
			(stroke
				(width 0.1)
				(type default)
			)
			(layer "B.Fab")
		)
		(fp_line
			(start -0.12065 -0.2794)
			(end -0.12065 -0.3048)
			(stroke
				(width 0.1)
				(type default)
			)
			(layer "B.Fab")
		)
		(fp_line
			(start -0.120396 0.2794)
			(end 0.12065 0.2794)
			(stroke
				(width 0.1)
				(type default)
			)
			(layer "B.Fab")
		)
		(fp_line
			(start -0.120396 0.3048)
			(end -0.120396 0.2794)
			(stroke
				(width 0.1)
				(type default)
			)
			(layer "B.Fab")
		)
		(fp_line
			(start 0.12065 -0.305054)
			(end 0.12065 -0.2794)
			(stroke
				(width 0.1)
				(type default)
			)
			(layer "B.Fab")
		)
		(fp_line
			(start 0.12065 -0.2794)
			(end -0.12065 -0.2794)
			(stroke
				(width 0.1)
				(type default)
			)
			(layer "B.Fab")
		)
		(fp_line
			(start 0.12065 0.2794)
			(end 0.12065 0.3048)
			(stroke
				(width 0.1)
				(type default)
			)
			(layer "B.Fab")
		)
		(fp_line
			(start 0.12065 0.3048)
			(end 0.67945 0.3048)
			(stroke
				(width 0.1)
				(type default)
			)
			(layer "B.Fab")
		)
		(fp_line
			(start 0.67945 -0.305054)
			(end 0.12065 -0.305054)
			(stroke
				(width 0.1)
				(type default)
			)
			(layer "B.Fab")
		)
		(fp_line
			(start 0.67945 0.3048)
			(end 0.67945 -0.305054)
			(stroke
				(width 0.1)
				(type default)
			)
			(layer "B.Fab")
		)
		(pad "1" smd circle
			(at 0.40005 0 180)
			(size 0 0)
			(layers "B.Cu" "B.Mask" "B.Paste")
			(net "PVDDCR_CPU1_P1")
		)
		(pad "2" smd circle
			(at -0.40005 0 180)
			(size 0 0)
			(layers "B.Cu" "B.Mask" "B.Paste")
			(net "GND")
		)
	)
	(footprint ""
		(layer "B.Cu")
		(at 211.69503 -57.078372 -90)
		(property "Reference" "R3752"
			(at 0 0 90)
			(layer "B.SilkS")
			(hide yes)
			(effects
				(font
					(size 1.27 1.27)
				)
				(justify mirror)
			)
		)
		(property "Value" ""
			(at 0 0 90)
			(layer "B.Fab")
			(effects
				(font
					(size 1.27 1.27)
				)
				(justify mirror)
			)
		)
		(duplicate_pad_numbers_are_jumpers no)
		(fp_line
			(start -0.7874 0.4064)
			(end 0.7874 0.4064)
			(stroke
				(width 0.1524)
				(type default)
			)
			(layer "B.SilkS")
		)
		(fp_line
			(start 0.7874 0.4064)
			(end 0.7874 -0.4064)
			(stroke
				(width 0.1524)
				(type default)
			)
			(layer "B.SilkS")
		)
		(fp_line
			(start -0.7874 -0.4064)
			(end -0.7874 0.4064)
			(stroke
				(width 0.1524)
				(type default)
			)
			(layer "B.SilkS")
		)
		(fp_line
			(start 0.7874 -0.4064)
			(end -0.7874 -0.4064)
			(stroke
				(width 0.1524)
				(type default)
			)
			(layer "B.SilkS")
		)
		(fp_line
			(start -0.67945 0.3048)
			(end -0.120396 0.3048)
			(stroke
				(width 0.1)
				(type default)
			)
			(layer "B.Fab")
		)
		(fp_line
			(start -0.120396 0.3048)
			(end -0.120396 0.2794)
			(stroke
				(width 0.1)
				(type default)
			)
			(layer "B.Fab")
		)
		(fp_line
			(start 0.12065 0.3048)
			(end 0.67945 0.3048)
			(stroke
				(width 0.1)
				(type default)
			)
			(layer "B.Fab")
		)
		(fp_line
			(start 0.67945 0.3048)
			(end 0.67945 -0.305054)
			(stroke
				(width 0.1)
				(type default)
			)
			(layer "B.Fab")
		)
		(fp_line
			(start -0.120396 0.2794)
			(end 0.12065 0.2794)
			(stroke
				(width 0.1)
				(type default)
			)
			(layer "B.Fab")
		)
		(fp_line
			(start 0.12065 0.2794)
			(end 0.12065 0.3048)
			(stroke
				(width 0.1)
				(type default)
			)
			(layer "B.Fab")
		)
		(fp_line
			(start -0.12065 -0.2794)
			(end -0.12065 -0.3048)
			(stroke
				(width 0.1)
				(type default)
			)
			(layer "B.Fab")
		)
		(fp_line
			(start 0.12065 -0.2794)
			(end -0.12065 -0.2794)
			(stroke
				(width 0.1)
				(type default)
			)
			(layer "B.Fab")
		)
		(fp_line
			(start -0.67945 -0.3048)
			(end -0.67945 0.3048)
			(stroke
				(width 0.1)
				(type default)
			)
			(layer "B.Fab")
		)
		(fp_line
			(start -0.12065 -0.3048)
			(end -0.67945 -0.3048)
			(stroke
				(width 0.1)
				(type default)
			)
			(layer "B.Fab")
		)
		(fp_line
			(start 0.12065 -0.305054)
			(end 0.12065 -0.2794)
			(stroke
				(width 0.1)
				(type default)
			)
			(layer "B.Fab")
		)
		(fp_line
			(start 0.67945 -0.305054)
			(end 0.12065 -0.305054)
			(stroke
				(width 0.1)
				(type default)
			)
			(layer "B.Fab")
		)
		(pad "1" smd circle
			(at 0.40005 0 90)
			(size 0 0)
			(layers "B.Cu" "B.Mask" "B.Paste")
			(net "E1S_0_P3V3_ADC_ALERT_R")
		)
		(pad "2" smd circle
			(at -0.40005 0 90)
			(size 0 0)
			(layers "B.Cu" "B.Mask" "B.Paste")
			(net "E1S_0_P3V3_P12V_ADC_R_ALERT")
		)
	)
)
